FILE_TYPE = MACRO_DRAWING;
SET COLOR_WIRE YELLOW;
SET COLOR_PROP ORANGE;
SET COLOR_DOT WHITE;
SET COLOR_ARC YELLOW;
SET COLOR_BODY GREEN;
SET COLOR_NOTE PURPLE;
SET PROP_DISPLAY VALUE;
SET PAGE_NUMBER P2;
FORCEADD QUANTA_TITLE_BLOCK_C..2
(1725 900);
FORCEPROP 1 LAST Q_TITLE TABLE OF CONTENT 1/3
J 0
(-7591 951);
DISPLAY 2.446809 (-7591 951);
PAINT GREEN (-7591 951);
FORCEPROP 2 LAST Q_DESIGNER SEAN
J 0
(-1474 1051);
DISPLAY 0.978723 (-1474 1051);
PAINT GREEN (-1474 1051);
FORCEPROP 1 LAST CUSTOM_TXT_CDS <CON_TC_SNO120>
J 2
(-975 2575);
FORCEPROP 1 LAST CUSTOM_TXT_CDS <CON_TC_SNO119>
J 2
(-975 2675);
FORCEPROP 1 LAST CUSTOM_TXT_CDS <CON_TC_SNO118>
J 2
(-975 2775);
FORCEPROP 1 LAST CUSTOM_TXT_CDS <CON_TC_SNO117>
J 2
(-975 2875);
FORCEPROP 1 LAST CUSTOM_TXT_CDS <CON_TC_SNO116>
J 2
(-975 2975);
FORCEPROP 1 LAST CUSTOM_TXT_CDS <CON_TC_SNO115>
J 2
(-975 3075);
FORCEPROP 1 LAST CUSTOM_TXT_CDS <CON_TC_SNO114>
J 2
(-975 3175);
FORCEPROP 1 LAST CUSTOM_TXT_CDS <CON_TC_SNO113>
J 2
(-975 3275);
FORCEPROP 1 LAST CUSTOM_TXT_CDS <CON_TC_SNO112>
J 2
(-975 3375);
FORCEPROP 1 LAST CUSTOM_TXT_CDS <CON_TC_SNO111>
J 2
(-975 3475);
FORCEPROP 1 LAST CUSTOM_TXT_CDS <CON_TC_SNO110>
J 2
(-975 3575);
FORCEPROP 1 LAST CUSTOM_TXT_CDS <CON_TC_SNO109>
J 2
(-975 3675);
FORCEPROP 1 LAST CUSTOM_TXT_CDS <CON_TC_SNO108>
J 2
(-975 3775);
FORCEPROP 1 LAST CUSTOM_TXT_CDS <CON_TC_SNO107>
J 2
(-975 3875);
FORCEPROP 1 LAST CUSTOM_TXT_CDS <CON_TC_SNO106>
J 2
(-975 3975);
FORCEPROP 1 LAST CUSTOM_TXT_CDS <CON_TC_SNO105>
J 2
(-975 4075);
FORCEPROP 1 LAST CUSTOM_TXT_CDS <CON_TC_SNO104>
J 2
(-975 4175);
FORCEPROP 1 LAST CUSTOM_TXT_CDS <CON_TC_SNO103>
J 2
(-975 4275);
FORCEPROP 1 LAST CUSTOM_TXT_CDS <CON_TC_SNO102>
J 2
(-975 4375);
FORCEPROP 1 LAST CUSTOM_TXT_CDS <CON_TC_SNO101>
J 2
(-975 4475);
FORCEPROP 1 LAST CUSTOM_TXT_CDS <CON_TC_SNO100>
J 2
(-975 4575);
FORCEPROP 1 LAST CUSTOM_TXT_CDS <CON_TC_SNO99>
J 2
(-975 4675);
FORCEPROP 1 LAST CUSTOM_TXT_CDS <CON_TC_SNO98>
J 2
(-975 4775);
FORCEPROP 1 LAST CUSTOM_TXT_CDS <CON_TC_SNO97>
J 2
(-975 4875);
FORCEPROP 1 LAST CUSTOM_TXT_CDS <CON_TC_SNO96>
J 2
(-975 4975);
FORCEPROP 1 LAST CUSTOM_TXT_CDS <CON_TC_SNO95>
J 2
(-975 5075);
FORCEPROP 1 LAST CUSTOM_TXT_CDS <CON_TC_SNO94>
J 2
(-975 5175);
FORCEPROP 1 LAST CUSTOM_TXT_CDS <CON_TC_SNO93>
J 2
(-975 5275);
FORCEPROP 1 LAST CUSTOM_TXT_CDS <CON_TC_SNO92>
J 2
(-975 5375);
FORCEPROP 1 LAST CUSTOM_TXT_CDS <CON_TC_SNO91>
J 2
(-975 5475);
FORCEPROP 1 LAST CUSTOM_TXT_CDS <CON_TC_SNO90>
J 2
(-975 5575);
FORCEPROP 1 LAST CUSTOM_TXT_CDS <CON_TC_SNO89>
J 2
(-975 5675);
FORCEPROP 1 LAST CUSTOM_TXT_CDS <CON_TC_SNO88>
J 2
(-975 5775);
FORCEPROP 1 LAST CUSTOM_TXT_CDS <CON_TC_SNO87>
J 2
(-975 5875);
FORCEPROP 1 LAST CUSTOM_TXT_CDS <CON_TC_SNO86>
J 2
(-975 5975);
FORCEPROP 1 LAST CUSTOM_TXT_CDS <CON_TC_SNO85>
J 2
(-975 6075);
FORCEPROP 1 LAST CUSTOM_TXT_CDS <CON_TC_SNO84>
J 2
(-975 6175);
FORCEPROP 1 LAST CUSTOM_TXT_CDS <CON_TC_SNO83>
J 2
(-975 6275);
FORCEPROP 1 LAST CUSTOM_TXT_CDS <CON_TC_SNO82>
J 2
(-975 6375);
FORCEPROP 1 LAST CUSTOM_TXT_CDS <CON_TC_SNO81>
J 2
(-975 6475);
FORCEPROP 1 LAST CUSTOM_TXT_CDS <CON_TC_SNO80>
J 2
(-3475 2575);
FORCEPROP 1 LAST CUSTOM_TXT_CDS <CON_TC_SNO79>
J 2
(-3475 2675);
FORCEPROP 1 LAST CUSTOM_TXT_CDS <CON_TC_SNO78>
J 2
(-3475 2775);
FORCEPROP 1 LAST CUSTOM_TXT_CDS <CON_TC_SNO77>
J 2
(-3475 2875);
FORCEPROP 1 LAST CUSTOM_TXT_CDS <CON_TC_SNO76>
J 2
(-3475 2975);
FORCEPROP 1 LAST CUSTOM_TXT_CDS <CON_TC_SNO75>
J 2
(-3475 3075);
FORCEPROP 1 LAST CUSTOM_TXT_CDS <CON_TC_SNO74>
J 2
(-3475 3175);
FORCEPROP 1 LAST CUSTOM_TXT_CDS <CON_TC_SNO73>
J 2
(-3475 3275);
FORCEPROP 1 LAST CUSTOM_TXT_CDS <CON_TC_SNO72>
J 2
(-3475 3375);
FORCEPROP 1 LAST CUSTOM_TXT_CDS <CON_TC_SNO71>
J 2
(-3475 3475);
FORCEPROP 1 LAST CUSTOM_TXT_CDS <CON_TC_SNO70>
J 2
(-3475 3575);
FORCEPROP 1 LAST CUSTOM_TXT_CDS <CON_TC_SNO69>
J 2
(-3475 3675);
FORCEPROP 1 LAST CUSTOM_TXT_CDS <CON_TC_SNO68>
J 2
(-3475 3775);
FORCEPROP 1 LAST CUSTOM_TXT_CDS <CON_TC_SNO67>
J 2
(-3475 3875);
FORCEPROP 1 LAST CUSTOM_TXT_CDS <CON_TC_SNO66>
J 2
(-3475 3975);
FORCEPROP 1 LAST CUSTOM_TXT_CDS <CON_TC_SNO65>
J 2
(-3475 4075);
FORCEPROP 1 LAST CUSTOM_TXT_CDS <CON_TC_SNO64>
J 2
(-3475 4175);
FORCEPROP 1 LAST CUSTOM_TXT_CDS <CON_TC_SNO63>
J 2
(-3475 4275);
FORCEPROP 1 LAST CUSTOM_TXT_CDS <CON_TC_SNO62>
J 2
(-3475 4375);
FORCEPROP 1 LAST CUSTOM_TXT_CDS <CON_TC_SNO61>
J 2
(-3475 4475);
FORCEPROP 1 LAST CUSTOM_TXT_CDS <CON_TC_SNO60>
J 2
(-3475 4575);
FORCEPROP 1 LAST CUSTOM_TXT_CDS <CON_TC_SNO59>
J 2
(-3475 4675);
FORCEPROP 1 LAST CUSTOM_TXT_CDS <CON_TC_SNO58>
J 2
(-3475 4775);
FORCEPROP 1 LAST CUSTOM_TXT_CDS <CON_TC_SNO57>
J 2
(-3475 4875);
FORCEPROP 1 LAST CUSTOM_TXT_CDS <CON_TC_SNO56>
J 2
(-3475 4975);
FORCEPROP 1 LAST CUSTOM_TXT_CDS <CON_TC_SNO55>
J 2
(-3475 5075);
FORCEPROP 1 LAST CUSTOM_TXT_CDS <CON_TC_SNO54>
J 2
(-3475 5175);
FORCEPROP 1 LAST CUSTOM_TXT_CDS <CON_TC_SNO53>
J 2
(-3475 5275);
FORCEPROP 1 LAST CUSTOM_TXT_CDS <CON_TC_SNO52>
J 2
(-3475 5375);
FORCEPROP 1 LAST CUSTOM_TXT_CDS <CON_TC_SNO51>
J 2
(-3475 5475);
FORCEPROP 1 LAST CUSTOM_TXT_CDS <CON_TC_SNO50>
J 2
(-3475 5575);
FORCEPROP 1 LAST CUSTOM_TXT_CDS <CON_TC_SNO49>
J 2
(-3475 5675);
FORCEPROP 1 LAST CUSTOM_TXT_CDS <CON_TC_SNO48>
J 2
(-3475 5775);
FORCEPROP 1 LAST CUSTOM_TXT_CDS <CON_TC_SNO47>
J 2
(-3475 5875);
FORCEPROP 1 LAST CUSTOM_TXT_CDS <CON_TC_SNO46>
J 2
(-3475 5975);
FORCEPROP 1 LAST CUSTOM_TXT_CDS <CON_TC_SNO45>
J 2
(-3475 6075);
FORCEPROP 1 LAST CUSTOM_TXT_CDS <CON_TC_SNO44>
J 2
(-3475 6175);
FORCEPROP 1 LAST CUSTOM_TXT_CDS <CON_TC_SNO43>
J 2
(-3475 6275);
FORCEPROP 1 LAST CUSTOM_TXT_CDS <CON_TC_SNO42>
J 2
(-3475 6375);
FORCEPROP 1 LAST CUSTOM_TXT_CDS <CON_TC_SNO41>
J 2
(-3475 6475);
FORCEPROP 1 LAST CUSTOM_TXT_CDS <CON_TC_SNO40>
J 2
(-5975 2575);
FORCEPROP 1 LAST CUSTOM_TXT_CDS <CON_TC_SNO39>
J 2
(-5975 2675);
FORCEPROP 1 LAST CUSTOM_TXT_CDS <CON_TC_SNO38>
J 2
(-5975 2775);
FORCEPROP 1 LAST CUSTOM_TXT_CDS <CON_TC_SNO37>
J 2
(-5975 2875);
FORCEPROP 1 LAST CUSTOM_TXT_CDS <CON_TC_SNO36>
J 2
(-5975 2975);
FORCEPROP 1 LAST CUSTOM_TXT_CDS <CON_TC_SNO35>
J 2
(-5975 3075);
FORCEPROP 1 LAST CUSTOM_TXT_CDS <CON_TC_SNO34>
J 2
(-5975 3175);
FORCEPROP 1 LAST CUSTOM_TXT_CDS <CON_TC_SNO33>
J 2
(-5975 3275);
FORCEPROP 1 LAST CUSTOM_TXT_CDS <CON_TC_SNO32>
J 2
(-5975 3375);
FORCEPROP 1 LAST CUSTOM_TXT_CDS <CON_TC_SNO31>
J 2
(-5975 3475);
FORCEPROP 1 LAST CUSTOM_TXT_CDS <CON_TC_SNO30>
J 2
(-5975 3575);
FORCEPROP 1 LAST CUSTOM_TXT_CDS <CON_TC_SNO29>
J 2
(-5975 3675);
FORCEPROP 1 LAST CUSTOM_TXT_CDS <CON_TC_SNO28>
J 2
(-5975 3775);
FORCEPROP 1 LAST CUSTOM_TXT_CDS <CON_TC_SNO27>
J 2
(-5975 3875);
FORCEPROP 1 LAST CUSTOM_TXT_CDS <CON_TC_SNO26>
J 2
(-5975 3975);
FORCEPROP 1 LAST CUSTOM_TXT_CDS <CON_TC_SNO25>
J 2
(-5975 4075);
FORCEPROP 1 LAST CUSTOM_TXT_CDS <CON_TC_SNO24>
J 2
(-5975 4175);
FORCEPROP 1 LAST CUSTOM_TXT_CDS <CON_TC_SNO23>
J 2
(-5975 4275);
FORCEPROP 1 LAST CUSTOM_TXT_CDS <CON_TC_SNO22>
J 2
(-5975 4375);
FORCEPROP 1 LAST CUSTOM_TXT_CDS <CON_TC_SNO21>
J 2
(-5975 4475);
FORCEPROP 1 LAST CUSTOM_TXT_CDS <CON_TC_SNO20>
J 2
(-5975 4575);
FORCEPROP 1 LAST CUSTOM_TXT_CDS <CON_TC_SNO19>
J 2
(-5975 4675);
FORCEPROP 1 LAST CUSTOM_TXT_CDS <CON_TC_SNO18>
J 2
(-5975 4775);
FORCEPROP 1 LAST CUSTOM_TXT_CDS <CON_TC_SNO17>
J 2
(-5975 4875);
FORCEPROP 1 LAST CUSTOM_TXT_CDS <CON_TC_SNO16>
J 2
(-5975 4975);
FORCEPROP 1 LAST CUSTOM_TXT_CDS <CON_TC_SNO15>
J 2
(-5975 5075);
FORCEPROP 1 LAST CUSTOM_TXT_CDS <CON_TC_SNO14>
J 2
(-5975 5175);
FORCEPROP 1 LAST CUSTOM_TXT_CDS <CON_TC_SNO13>
J 2
(-5975 5275);
FORCEPROP 1 LAST CUSTOM_TXT_CDS <CON_TC_SNO12>
J 2
(-5975 5375);
FORCEPROP 1 LAST CUSTOM_TXT_CDS <CON_TC_SNO11>
J 2
(-5975 5475);
FORCEPROP 1 LAST CUSTOM_TXT_CDS <CON_TC_SNO10>
J 2
(-5975 5575);
FORCEPROP 1 LAST CUSTOM_TXT_CDS <CON_TC_SNO9>
J 2
(-5975 5675);
FORCEPROP 1 LAST CUSTOM_TXT_CDS <CON_TC_SNO8>
J 2
(-5975 5775);
FORCEPROP 1 LAST CUSTOM_TXT_CDS <CON_TC_SNO7>
J 2
(-5975 5875);
FORCEPROP 1 LAST CUSTOM_TXT_CDS <CON_TC_SNO6>
J 2
(-5975 5975);
FORCEPROP 1 LAST CUSTOM_TXT_CDS <CON_TC_SNO5>
J 2
(-5975 6075);
FORCEPROP 1 LAST CUSTOM_TXT_CDS <CON_TC_SNO4>
J 2
(-5975 6175);
FORCEPROP 1 LAST CUSTOM_TXT_CDS <CON_TC_SNO3>
J 2
(-5975 6275);
FORCEPROP 1 LAST CUSTOM_TXT_CDS <CON_TC_SNO2>
J 2
(-5975 6375);
FORCEPROP 1 LAST CUSTOM_TXT_CDS <CON_TC_SNO1>
J 2
(-5975 6475);
FORCEPROP 1 LAST CUSTOM_TXT_CDS <CON_TC_SNM120>
J 0
(-875 2575);
FORCEPROP 1 LAST CUSTOM_TXT_CDS <CON_TC_SNM119>
J 0
(-875 2675);
FORCEPROP 1 LAST CUSTOM_TXT_CDS <CON_TC_SNM118>
J 0
(-875 2775);
FORCEPROP 1 LAST CUSTOM_TXT_CDS <CON_TC_SNM117>
J 0
(-875 2875);
FORCEPROP 1 LAST CUSTOM_TXT_CDS <CON_TC_SNM116>
J 0
(-875 2975);
FORCEPROP 1 LAST CUSTOM_TXT_CDS <CON_TC_SNM115>
J 0
(-875 3075);
FORCEPROP 1 LAST CUSTOM_TXT_CDS <CON_TC_SNM114>
J 0
(-875 3175);
FORCEPROP 1 LAST CUSTOM_TXT_CDS <CON_TC_SNM113>
J 0
(-875 3275);
FORCEPROP 1 LAST CUSTOM_TXT_CDS <CON_TC_SNM112>
J 0
(-875 3375);
FORCEPROP 1 LAST CUSTOM_TXT_CDS <CON_TC_SNM111>
J 0
(-875 3475);
FORCEPROP 1 LAST CUSTOM_TXT_CDS <CON_TC_SNM110>
J 0
(-875 3575);
FORCEPROP 1 LAST CUSTOM_TXT_CDS <CON_TC_SNM109>
J 0
(-875 3675);
FORCEPROP 1 LAST CUSTOM_TXT_CDS <CON_TC_SNM108>
J 0
(-875 3775);
FORCEPROP 1 LAST CUSTOM_TXT_CDS <CON_TC_SNM107>
J 0
(-875 3875);
FORCEPROP 1 LAST CUSTOM_TXT_CDS <CON_TC_SNM106>
J 0
(-875 3975);
FORCEPROP 1 LAST CUSTOM_TXT_CDS <CON_TC_SNM105>
J 0
(-875 4075);
FORCEPROP 1 LAST CUSTOM_TXT_CDS <CON_TC_SNM104>
J 0
(-875 4175);
FORCEPROP 1 LAST CUSTOM_TXT_CDS <CON_TC_SNM103>
J 0
(-875 4275);
FORCEPROP 1 LAST CUSTOM_TXT_CDS <CON_TC_SNM102>
J 0
(-875 4375);
FORCEPROP 1 LAST CUSTOM_TXT_CDS <CON_TC_SNM101>
J 0
(-875 4475);
FORCEPROP 1 LAST CUSTOM_TXT_CDS <CON_TC_SNM100>
J 0
(-875 4575);
FORCEPROP 1 LAST CUSTOM_TXT_CDS <CON_TC_SNM99>
J 0
(-875 4675);
FORCEPROP 1 LAST CUSTOM_TXT_CDS <CON_TC_SNM98>
J 0
(-875 4775);
FORCEPROP 1 LAST CUSTOM_TXT_CDS <CON_TC_SNM97>
J 0
(-875 4875);
FORCEPROP 1 LAST CUSTOM_TXT_CDS <CON_TC_SNM96>
J 0
(-875 4975);
FORCEPROP 1 LAST CUSTOM_TXT_CDS <CON_TC_SNM95>
J 0
(-875 5075);
FORCEPROP 1 LAST CUSTOM_TXT_CDS <CON_TC_SNM94>
J 0
(-875 5175);
FORCEPROP 1 LAST CUSTOM_TXT_CDS <CON_TC_SNM93>
J 0
(-875 5275);
FORCEPROP 1 LAST CUSTOM_TXT_CDS <CON_TC_SNM92>
J 0
(-875 5375);
FORCEPROP 1 LAST CUSTOM_TXT_CDS <CON_TC_SNM91>
J 0
(-875 5475);
FORCEPROP 1 LAST CUSTOM_TXT_CDS <CON_TC_SNM90>
J 0
(-875 5575);
FORCEPROP 1 LAST CUSTOM_TXT_CDS <CON_TC_SNM89>
J 0
(-875 5675);
FORCEPROP 1 LAST CUSTOM_TXT_CDS <CON_TC_SNM88>
J 0
(-875 5775);
FORCEPROP 1 LAST CUSTOM_TXT_CDS <CON_TC_SNM87>
J 0
(-875 5875);
FORCEPROP 1 LAST CUSTOM_TXT_CDS <CON_TC_SNM86>
J 0
(-875 5975);
FORCEPROP 1 LAST CUSTOM_TXT_CDS <CON_TC_SNM85>
J 0
(-875 6075);
FORCEPROP 1 LAST CUSTOM_TXT_CDS <CON_TC_SNM84>
J 0
(-875 6175);
FORCEPROP 1 LAST CUSTOM_TXT_CDS <CON_TC_SNM83>
J 0
(-875 6275);
FORCEPROP 1 LAST CUSTOM_TXT_CDS <CON_TC_SNM82>
J 0
(-875 6375);
FORCEPROP 1 LAST CUSTOM_TXT_CDS <CON_TC_SNM81>
J 0
(-875 6475);
FORCEPROP 1 LAST CUSTOM_TXT_CDS <CON_TC_SNM79>
J 0
(-3375 2675);
FORCEPROP 1 LAST CUSTOM_TXT_CDS <CON_TC_SNM78>
J 0
(-3375 2775);
FORCEPROP 1 LAST CUSTOM_TXT_CDS <CON_TC_SNM77>
J 0
(-3375 2875);
FORCEPROP 1 LAST CUSTOM_TXT_CDS <CON_TC_SNM76>
J 0
(-3375 2975);
FORCEPROP 1 LAST CUSTOM_TXT_CDS <CON_TC_SNM75>
J 0
(-3375 3075);
FORCEPROP 1 LAST CUSTOM_TXT_CDS <CON_TC_SNM74>
J 0
(-3375 3175);
FORCEPROP 1 LAST CUSTOM_TXT_CDS <CON_TC_SNM73>
J 0
(-3375 3275);
FORCEPROP 1 LAST CUSTOM_TXT_CDS <CON_TC_SNM72>
J 0
(-3375 3375);
FORCEPROP 1 LAST CUSTOM_TXT_CDS <CON_TC_SNM71>
J 0
(-3375 3475);
FORCEPROP 1 LAST CUSTOM_TXT_CDS <CON_TC_SNM70>
J 0
(-3375 3575);
FORCEPROP 1 LAST CUSTOM_TXT_CDS <CON_TC_SNM69>
J 0
(-3375 3675);
FORCEPROP 1 LAST CUSTOM_TXT_CDS <CON_TC_SNM68>
J 0
(-3375 3775);
FORCEPROP 1 LAST CUSTOM_TXT_CDS <CON_TC_SNM67>
J 0
(-3375 3875);
FORCEPROP 1 LAST CUSTOM_TXT_CDS <CON_TC_SNM66>
J 0
(-3375 3975);
FORCEPROP 1 LAST CUSTOM_TXT_CDS <CON_TC_SNM65>
J 0
(-3375 4075);
FORCEPROP 1 LAST CUSTOM_TXT_CDS <CON_TC_SNM64>
J 0
(-3375 4175);
FORCEPROP 1 LAST CUSTOM_TXT_CDS <CON_TC_SNM63>
J 0
(-3375 4275);
FORCEPROP 1 LAST CUSTOM_TXT_CDS <CON_TC_SNM62>
J 0
(-3375 4375);
FORCEPROP 1 LAST CUSTOM_TXT_CDS <CON_TC_SNM61>
J 0
(-3375 4475);
FORCEPROP 1 LAST CUSTOM_TXT_CDS <CON_TC_SNM60>
J 0
(-3375 4575);
FORCEPROP 1 LAST CUSTOM_TXT_CDS <CON_TC_SNM59>
J 0
(-3375 4675);
FORCEPROP 1 LAST CUSTOM_TXT_CDS <CON_TC_SNM58>
J 0
(-3375 4775);
FORCEPROP 1 LAST CUSTOM_TXT_CDS <CON_TC_SNM57>
J 0
(-3375 4875);
FORCEPROP 1 LAST CUSTOM_TXT_CDS <CON_TC_SNM56>
J 0
(-3375 4975);
FORCEPROP 1 LAST CUSTOM_TXT_CDS <CON_TC_SNM55>
J 0
(-3375 5075);
FORCEPROP 1 LAST CUSTOM_TXT_CDS <CON_TC_SNM54>
J 0
(-3375 5175);
FORCEPROP 1 LAST CUSTOM_TXT_CDS <CON_TC_SNM53>
J 0
(-3375 5275);
FORCEPROP 1 LAST CUSTOM_TXT_CDS <CON_TC_SNM52>
J 0
(-3375 5375);
FORCEPROP 1 LAST CUSTOM_TXT_CDS <CON_TC_SNM51>
J 0
(-3375 5475);
FORCEPROP 1 LAST CUSTOM_TXT_CDS <CON_TC_SNM50>
J 0
(-3375 5575);
FORCEPROP 1 LAST CUSTOM_TXT_CDS <CON_TC_SNM49>
J 0
(-3375 5675);
FORCEPROP 1 LAST CUSTOM_TXT_CDS <CON_TC_SNM48>
J 0
(-3375 5775);
FORCEPROP 1 LAST CUSTOM_TXT_CDS <CON_TC_SNM47>
J 0
(-3375 5875);
FORCEPROP 1 LAST CUSTOM_TXT_CDS <CON_TC_SNM46>
J 0
(-3375 5975);
FORCEPROP 1 LAST CUSTOM_TXT_CDS <CON_TC_SNM45>
J 0
(-3375 6075);
FORCEPROP 1 LAST CUSTOM_TXT_CDS <CON_TC_SNM44>
J 0
(-3375 6175);
FORCEPROP 1 LAST CUSTOM_TXT_CDS <CON_TC_SNM43>
J 0
(-3375 6275);
FORCEPROP 1 LAST CUSTOM_TXT_CDS <CON_TC_SNM42>
J 0
(-3375 6375);
FORCEPROP 1 LAST CUSTOM_TXT_CDS <CON_TC_SNM41>
J 0
(-3375 6475);
FORCEPROP 1 LAST CUSTOM_TXT_CDS <CON_TC_SNM40>
J 0
(-5875 2575);
FORCEPROP 1 LAST CUSTOM_TXT_CDS <CON_TC_SNM39>
J 0
(-5875 2675);
FORCEPROP 1 LAST CUSTOM_TXT_CDS <CON_TC_SNM38>
J 0
(-5875 2775);
FORCEPROP 1 LAST CUSTOM_TXT_CDS <CON_TC_SNM37>
J 0
(-5875 2875);
FORCEPROP 1 LAST CUSTOM_TXT_CDS <CON_TC_SNM36>
J 0
(-5875 2975);
FORCEPROP 1 LAST CUSTOM_TXT_CDS <CON_TC_SNM35>
J 0
(-5875 3075);
FORCEPROP 1 LAST CUSTOM_TXT_CDS <CON_TC_SNM34>
J 0
(-5875 3175);
FORCEPROP 1 LAST CUSTOM_TXT_CDS <CON_TC_SNM33>
J 0
(-5875 3275);
FORCEPROP 1 LAST CUSTOM_TXT_CDS <CON_TC_SNM32>
J 0
(-5875 3375);
FORCEPROP 1 LAST CUSTOM_TXT_CDS <CON_TC_SNM30>
J 0
(-5875 3575);
FORCEPROP 1 LAST CUSTOM_TXT_CDS <CON_TC_SNM28>
J 0
(-5875 3775);
FORCEPROP 1 LAST CUSTOM_TXT_CDS <CON_TC_SNM27>
J 0
(-5875 3875);
FORCEPROP 1 LAST CUSTOM_TXT_CDS <CON_TC_SNM26>
J 0
(-5875 3975);
FORCEPROP 1 LAST CUSTOM_TXT_CDS <CON_TC_SNM25>
J 0
(-5875 4075);
FORCEPROP 1 LAST CUSTOM_TXT_CDS <CON_TC_SNM23>
J 0
(-5875 4275);
FORCEPROP 1 LAST CUSTOM_TXT_CDS <CON_TC_SNM22>
J 0
(-5875 4375);
FORCEPROP 1 LAST CUSTOM_TXT_CDS <CON_TC_SNM21>
J 0
(-5875 4475);
FORCEPROP 1 LAST CUSTOM_TXT_CDS <CON_TC_SNM20>
J 0
(-5875 4575);
FORCEPROP 1 LAST CUSTOM_TXT_CDS <CON_TC_SNM19>
J 0
(-5875 4675);
FORCEPROP 1 LAST CUSTOM_TXT_CDS <CON_TC_SNM18>
J 0
(-5875 4775);
FORCEPROP 1 LAST CUSTOM_TXT_CDS <CON_TC_SNM17>
J 0
(-5875 4875);
FORCEPROP 1 LAST CUSTOM_TXT_CDS <CON_TC_SNM16>
J 0
(-5875 4975);
FORCEPROP 1 LAST CUSTOM_TXT_CDS <CON_TC_SNM15>
J 0
(-5875 5075);
FORCEPROP 1 LAST CUSTOM_TXT_CDS <CON_TC_SNM14>
J 0
(-5875 5175);
FORCEPROP 1 LAST CUSTOM_TXT_CDS <CON_TC_SNM13>
J 0
(-5875 5275);
FORCEPROP 1 LAST CUSTOM_TXT_CDS <CON_TC_SNM12>
J 0
(-5875 5375);
FORCEPROP 1 LAST CUSTOM_TXT_CDS <CON_TC_SNM11>
J 0
(-5875 5475);
FORCEPROP 1 LAST CUSTOM_TXT_CDS <CON_TC_SNM10>
J 0
(-5875 5575);
FORCEPROP 1 LAST CUSTOM_TXT_CDS <CON_TC_SNM9>
J 0
(-5875 5675);
FORCEPROP 1 LAST CUSTOM_TXT_CDS <CON_TC_SNM8>
J 0
(-5875 5775);
FORCEPROP 1 LAST CUSTOM_TXT_CDS <CON_TC_SNM7>
J 0
(-5875 5875);
FORCEPROP 1 LAST CUSTOM_TXT_CDS <CON_TC_SNM6>
J 0
(-5875 5975);
FORCEPROP 1 LAST CUSTOM_TXT_CDS <CON_TC_SNM5>
J 0
(-5875 6075);
FORCEPROP 1 LAST CUSTOM_TXT_CDS <CON_TC_SNM4>
J 0
(-5875 6175);
FORCEPROP 1 LAST CUSTOM_TXT_CDS <CON_TC_SNM3>
J 0
(-5875 6275);
FORCEPROP 1 LAST CUSTOM_TXT_CDS <CON_TC_SNM2>
J 0
(-5875 6375);
FORCEPROP 1 LAST CUSTOM_TXT_CDS <CON_TC_SNM1>
J 0
(-5875 6475);
FORCEPROP 1 LAST CUSTOM_TXT_CDS <CON_LAST_MODIFIED>
J 0
(-175 925);
DISPLAY 0.978723 (-175 925);
FORCEPROP 1 LAST CUSTOM_TXT_CDS <Q_NUMBER>
J 0
(325 1000);
DISPLAY 1.212766 (325 1000);
FORCEPROP 1 LAST CUSTOM_TXT_CDS <Q_PROJ>
J 0
(-650 1000);
DISPLAY 1.212766 (-650 1000);
FORCEPROP 1 LAST CUSTOM_TXT_CDS <Q_REV>
J 0
(1550 1000);
DISPLAY 1.212766 (1550 1000);
FORCEPROP 1 LAST CUSTOM_TXT_CDS <CON_PAGE_NUM> OF <CON_TOTAL_PAGES>
J 0
(1287 913);
DISPLAY 0.978723 (1287 913);
FORCEPROP 1 LAST CUSTOM_TXT_CDS <CON_TC_SNM24>
J 0
(-5875 4175);
FORCEPROP 1 LAST CUSTOM_TXT_CDS <CON_TC_SNM29>
J 0
(-5875 3675);
FORCEPROP 1 LAST CUSTOM_TXT_CDS <CON_TC_SNM31>
J 0
(-5875 3475);
FORCEPROP 1 LAST CUSTOM_TXT_CDS <CON_TC_SNM80>
J 0
(-3375 2575);
FORCEPROP 2 LAST Q_DEPT 
J 1
(-2026 949);
DISPLAY 1.957447 (-2026 949);
PAINT GREEN (-2026 949);
FORCEPROP 2 LAST CDS_LIB pure_quanta
J 0
(1725 900);
PAINT MONO (1725 900);
DISPLAY INVISIBLE (1725 900);
FORCEPROP 1 LAST TOC_SYMBOL TRUE
J 0
(-7449 7352);
DISPLAY 0.978723 (-7449 7352);
PAINT GREEN (-7449 7352);
DISPLAY INVISIBLE (-7449 7352);
FORCEPROP 2 LAST PAGE_BORDER TRUE
J 0
(-6165 6150);
DISPLAY 0.638298 (-6165 6150);
PAINT PINK (-6165 6150);
DISPLAY INVISIBLE (-6165 6150);
FORCEPROP 1 LAST COMMENT_BODY TRUE
J 0
(576 926);
DISPLAY 0.978723 (576 926);
PAINT GREEN (576 926);
DISPLAY INVISIBLE (576 926);
FORCEPROP 2 LAST CDS_XR_PAGE_TITLE CR-2 : @S9S_MB_2U_LIB.S9S_MB_2U(SCH_1):PAGE2
J 0
(-6165 6150);
DISPLAY 0.638298 (-6165 6150);
PAINT PINK (-6165 6150);
DISPLAY INVISIBLE (-6165 6150);
FORCEPROP 2 LAST CUSTOM_TXT_CDS <XR_PAGE_TITLE>
J 0
(-6165 6150);
DISPLAY 0.638298 (-6165 6150);
PAINT PINK (-6165 6150);
DISPLAY INVISIBLE (-6165 6150);
FORCEPROP 0 LAST CDS_CON_LAST_MODIFIED Thu Aug 24 16:11:55 2023
J 0
(-175 925);
PAINT MONO (-175 925);
DISPLAY INVISIBLE (-175 925);
QUIT
